(kicad_pcb
	(version 20241229)
	(generator "pcbnew")
	(generator_version "9.0")
	(general
		(thickness 1.61)
		(legacy_teardrops no)
	)
	(paper "A3")
	(title_block
		(title "RDIMM DDR5 Tester")
		(date "2026-05-21")
		(rev "2.2.0")
		(company "Antmicro")
		(comment 9 "footprints 337-340 of 796")
	)
	(layers
		(0 "F.Cu" signal)
		(4 "In1.Cu" power)
		(6 "In2.Cu" mixed)
		(8 "In3.Cu" power)
		(10 "In4.Cu" mixed)
		(12 "In5.Cu" power)
		(14 "In6.Cu" mixed)
		(16 "In7.Cu" power)
		(18 "In8.Cu" power)
		(20 "In9.Cu" mixed)
		(22 "In10.Cu" power)
		(2 "B.Cu" signal)
		(9 "F.Adhes" user "F.Adhesive")
		(11 "B.Adhes" user "B.Adhesive")
		(13 "F.Paste" user)
		(15 "B.Paste" user)
		(5 "F.SilkS" user "F.Silkscreen")
		(7 "B.SilkS" user "B.Silkscreen")
		(1 "F.Mask" user)
		(3 "B.Mask" user)
		(17 "Dwgs.User" user "User.Drawings")
		(19 "Cmts.User" user "User.Comments")
		(21 "Eco1.User" user "User.Eco1")
		(23 "Eco2.User" user "User.Eco2")
		(25 "Edge.Cuts" user)
		(27 "Margin" user)
		(31 "F.CrtYd" user "F.Courtyard")
		(29 "B.CrtYd" user "B.Courtyard")
		(35 "F.Fab" user)
		(33 "B.Fab" user)
	)
	(footprint "antmicro-footprints:TP_SMD_1mm"
		(layer "F.Cu")
		(at 244.025 153.025)
		(property "Reference" "TP13"
			(at 0 -0.731898 0)
			(layer "F.SilkS")
			(hide yes)
			(effects
				(font
					(size 0.7 0.7)
					(thickness 0.15)
				)
				(justify left bottom)
			)
		)
		(property "Value" "TP_1mm_SMD"
			(at 0 1.4 0)
			(layer "F.Fab")
			(effects
				(font
					(size 0.7 0.7)
					(thickness 0.15)
				)
				(justify left bottom)
			)
		)
		(property "MPN" ""
			(at 0 0 0)
			(unlocked yes)
			(layer "F.Fab")
			(hide yes)
			(effects
				(font
					(size 1 1)
					(thickness 0.15)
				)
			)
		)
		(property "Manufacturer" ""
			(at 0 0 0)
			(unlocked yes)
			(layer "F.Fab")
			(hide yes)
			(effects
				(font
					(size 1 1)
					(thickness 0.15)
				)
			)
		)
		(property "Author" "Antmicro"
			(at 0 0 0)
			(unlocked yes)
			(layer "F.Fab")
			(hide yes)
			(effects
				(font
					(size 1 1)
					(thickness 0.15)
				)
			)
		)
		(property "License" "Apache-2.0"
			(at 0 0 0)
			(unlocked yes)
			(layer "F.Fab")
			(hide yes)
			(effects
				(font
					(size 1 1)
					(thickness 0.15)
				)
			)
		)
		(sheetname "/Supply/DC-DC IO/")
		(sheetfile "dc-dc-io.kicad_sch")
		(attr exclude_from_pos_files)
		(fp_circle
			(center 0 0)
			(end 0.6 0)
			(stroke
				(width 0.05)
				(type default)
			)
			(fill no)
			(layer "F.CrtYd")
		)
		(fp_text user "${REFERENCE}"
			(at -0.5 2.8 0)
			(layer "F.Fab")
			(effects
				(font
					(size 0.7 0.7)
					(thickness 0.15)
				)
				(justify left bottom)
			)
		)
		(fp_text user "License: Apache-2.0"
			(at -0.5 5.2 0)
			(layer "F.Fab")
			(effects
				(font
					(size 0.7 0.7)
					(thickness 0.15)
				)
				(justify left bottom)
			)
		)
		(fp_text user "Author: Antmicro"
			(at -0.5 4 0)
			(layer "F.Fab")
			(effects
				(font
					(size 0.7 0.7)
					(thickness 0.15)
				)
				(justify left bottom)
			)
		)
		(pad "1" smd circle
			(at 0 0)
			(size 1 1)
			(layers "F.Cu" "F.Mask")
			(net 152 "+5V")
			(pinfunction "1")
			(pintype "passive")
		)
	)
	(footprint "antmicro-footprints:SC70-3"
		(layer "F.Cu")
		(at 250.274499 140.6)
		(property "Reference" "Q10"
			(at 0.505501 1.11 90)
			(layer "F.SilkS")
			(effects
				(font
					(size 0.7 0.7)
					(thickness 0.15)
				)
				(justify left bottom)
			)
		)
		(property "Value" "BSS138PW"
			(at 0 2.3 0)
			(layer "F.Fab")
			(effects
				(font
					(size 0.7 0.7)
					(thickness 0.15)
				)
				(justify left bottom)
			)
		)
		(property "Datasheet" "https://assets.nexperia.com/documents/data-sheet/BSS138PW.pdf"
			(at 0 0 0)
			(layer "F.Fab")
			(hide yes)
			(effects
				(font
					(size 1.27 1.27)
					(thickness 0.15)
				)
			)
		)
		(property "MPN" "BSS138PW"
			(at 0 0 0)
			(unlocked yes)
			(layer "F.Fab")
			(hide yes)
			(effects
				(font
					(size 1 1)
					(thickness 0.15)
				)
			)
		)
		(property "Manufacturer" "Nexperia"
			(at 0 0 0)
			(unlocked yes)
			(layer "F.Fab")
			(hide yes)
			(effects
				(font
					(size 1 1)
					(thickness 0.15)
				)
			)
		)
		(property "Author" "Antmicro"
			(at 0 0 0)
			(unlocked yes)
			(layer "F.Fab")
			(hide yes)
			(effects
				(font
					(size 1 1)
					(thickness 0.15)
				)
			)
		)
		(property "License" "Apache-2.0"
			(at 0 0 0)
			(unlocked yes)
			(layer "F.Fab")
			(hide yes)
			(effects
				(font
					(size 1 1)
					(thickness 0.15)
				)
			)
		)
		(sheetname "/DDR5 RDIMM/")
		(sheetfile "ddr5-rdimm.kicad_sch")
		(attr smd)
		(fp_line
			(start -0.3 -1)
			(end 0.627 -0.999)
			(stroke
				(width 0.15)
				(type solid)
			)
			(layer "F.SilkS")
		)
		(fp_line
			(start -0.3 1)
			(end 0.627 1.001)
			(stroke
				(width 0.15)
				(type solid)
			)
			(layer "F.SilkS")
		)
		(fp_line
			(start 0.627 -0.6)
			(end 0.627 -0.999)
			(stroke
				(width 0.15)
				(type solid)
			)
			(layer "F.SilkS")
		)
		(fp_line
			(start 0.627 0.6)
			(end 0.627 1.001)
			(stroke
				(width 0.15)
				(type solid)
			)
			(layer "F.SilkS")
		)
		(fp_line
			(start -1.4 1)
			(end -1.4 -1)
			(stroke
				(width 0.05)
				(type solid)
			)
			(layer "F.CrtYd")
		)
		(fp_line
			(start -0.9 -1.3)
			(end -0.9 -1)
			(stroke
				(width 0.05)
				(type solid)
			)
			(layer "F.CrtYd")
		)
		(fp_line
			(start -0.9 -1.3)
			(end 0.9 -1.3)
			(stroke
				(width 0.05)
				(type solid)
			)
			(layer "F.CrtYd")
		)
		(fp_line
			(start -0.9 -1)
			(end -1.4 -1)
			(stroke
				(width 0.05)
				(type solid)
			)
			(layer "F.CrtYd")
		)
		(fp_line
			(start -0.9 1)
			(end -1.4 1)
			(stroke
				(width 0.05)
				(type solid)
			)
			(layer "F.CrtYd")
		)
		(fp_line
			(start -0.9 1.3)
			(end -0.9 1)
			(stroke
				(width 0.05)
				(type solid)
			)
			(layer "F.CrtYd")
		)
		(fp_line
			(start 0.9 -1.3)
			(end 0.9 -0.4)
			(stroke
				(width 0.05)
				(type solid)
			)
			(layer "F.CrtYd")
		)
		(fp_line
			(start 0.9 -0.4)
			(end 1.4 -0.4)
			(stroke
				(width 0.05)
				(type solid)
			)
			(layer "F.CrtYd")
		)
		(fp_line
			(start 0.9 0.4)
			(end 0.9 1.3)
			(stroke
				(width 0.05)
				(type solid)
			)
			(layer "F.CrtYd")
		)
		(fp_line
			(start 0.9 1.3)
			(end -0.9 1.3)
			(stroke
				(width 0.05)
				(type solid)
			)
			(layer "F.CrtYd")
		)
		(fp_line
			(start 1.4 -0.4)
			(end 1.4 0.4)
			(stroke
				(width 0.05)
				(type solid)
			)
			(layer "F.CrtYd")
		)
		(fp_line
			(start 1.4 0.4)
			(end 0.9 0.4)
			(stroke
				(width 0.05)
				(type solid)
			)
			(layer "F.CrtYd")
		)
		(fp_rect
			(start -0.623 -0.999)
			(end 0.627 1.001)
			(stroke
				(width 0.15)
				(type solid)
			)
			(fill no)
			(layer "F.Fab")
		)
		(fp_text user "License: Apache-2.0"
			(at -1.45 6.782 0)
			(layer "F.Fab")
			(effects
				(font
					(size 0.7 0.7)
					(thickness 0.15)
				)
				(justify left bottom)
			)
		)
		(fp_text user "Author: Antmicro"
			(at -1.45 5.782 0)
			(layer "F.Fab")
			(effects
				(font
					(size 0.7 0.7)
					(thickness 0.15)
				)
				(justify left bottom)
			)
		)
		(fp_text user "${REFERENCE}"
			(at -1.45 4.783 0)
			(layer "F.Fab")
			(effects
				(font
					(size 0.7 0.7)
					(thickness 0.15)
				)
				(justify left bottom)
			)
		)
		(pad "1" smd rect
			(at -1.051 -0.65 90)
			(size 0.6 0.6)
			(layers "F.Cu" "F.Mask" "F.Paste")
			(net 180 "HOT_SWAP_GREEN")
			(pinfunction "G")
			(pintype "passive")
		)
		(pad "2" smd rect
			(at -1.051 0.65 90)
			(size 0.6 0.6)
			(layers "F.Cu" "F.Mask" "F.Paste")
			(net 1 "GND")
			(pinfunction "S")
			(pintype "passive")
		)
		(pad "3" smd rect
			(at 1.05 0 90)
			(size 0.6 0.6)
			(layers "F.Cu" "F.Mask" "F.Paste")
			(net 278 "Net-(Q10-D)")
			(pinfunction "D")
			(pintype "passive")
		)
	)
	(footprint "antmicro-footprints:NetTie-2_SMD_Pad0.127mm"
		(layer "F.Cu")
		(at 257.174 179.775)
		(descr "Net tie, 2 pin, 0.127mm  SMD pads")
		(tags "net tie")
		(property "Reference" "NT4"
			(at -0.128 -1.345 0)
			(layer "F.SilkS")
			(hide yes)
			(effects
				(font
					(size 0.7 0.7)
					(thickness 0.15)
				)
				(justify left bottom)
			)
		)
		(property "Value" "Net-Tie_P0.127mm"
			(at 0 1.199 0)
			(layer "F.Fab")
			(effects
				(font
					(size 0.7 0.7)
					(thickness 0.15)
				)
				(justify left bottom)
			)
		)
		(property "MPN" ""
			(at 0 0 0)
			(unlocked yes)
			(layer "F.Fab")
			(hide yes)
			(effects
				(font
					(size 1 1)
					(thickness 0.15)
				)
			)
		)
		(property "Manufacturer" ""
			(at 0 0 0)
			(unlocked yes)
			(layer "F.Fab")
			(hide yes)
			(effects
				(font
					(size 1 1)
					(thickness 0.15)
				)
			)
		)
		(property "Author" "Antmicro"
			(at 0 0 0)
			(unlocked yes)
			(layer "F.Fab")
			(hide yes)
			(effects
				(font
					(size 1 1)
					(thickness 0.15)
				)
			)
		)
		(property "License" "Apache-2.0"
			(at 0 0 0)
			(unlocked yes)
			(layer "F.Fab")
			(hide yes)
			(effects
				(font
					(size 1 1)
					(thickness 0.15)
				)
			)
		)
		(property ki_fp_filters "Net*Tie*")
		(sheetname "/Supply/DC-DC AUX, MGT/")
		(sheetfile "dc-dc-aux-mgt.kicad_sch")
		(attr through_hole exclude_from_pos_files exclude_from_bom)
		(net_tie_pad_groups "1, 2")
		(fp_poly
			(pts
				(xy -0.0635 -0.0635) (xy 0.0625 -0.0635) (xy 0.0625 0.0635) (xy -0.0635 0.0635)
			)
			(stroke
				(width 0)
				(type solid)
			)
			(fill yes)
			(layer "F.Cu")
		)
		(fp_poly
			(pts
				(xy 0.2 -0.16) (xy 0.29 -0.07) (xy 0.29 0.07) (xy 0.2 0.16) (xy -0.2 0.16) (xy -0.29 0.07) (xy -0.29 -0.06)
				(xy -0.19 -0.16)
			)
			(stroke
				(width 0.05)
				(type solid)
			)
			(fill no)
			(layer "F.CrtYd")
		)
		(fp_text user "${REFERENCE}"
			(at -0.128 3.2 0)
			(layer "F.Fab")
			(effects
				(font
					(size 0.7 0.7)
					(thickness 0.15)
				)
				(justify left bottom)
			)
		)
		(fp_text user "License: Apache-2.0"
			(at -0.128 5.6 0)
			(layer "F.Fab")
			(effects
				(font
					(size 0.7 0.7)
					(thickness 0.15)
				)
				(justify left bottom)
			)
		)
		(fp_text user "Author: Antmicro"
			(at -0.128 4.4 0)
			(layer "F.Fab")
			(effects
				(font
					(size 0.7 0.7)
					(thickness 0.15)
				)
				(justify left bottom)
			)
		)
		(pad "1" smd roundrect
			(at -0.127 0 180)
			(size 0.127 0.127)
			(layers "F.Cu")
			(roundrect_rratio 0.5)
			(chamfer_ratio 0)
			(chamfer top_left bottom_left)
			(net 684 "/Supply/DC-DC AUX, MGT/MGTAVCCAUX_SEN_+")
			(pinfunction "1")
			(pintype "passive")
		)
		(pad "2" smd roundrect
			(at 0.126 0)
			(size 0.127 0.127)
			(layers "F.Cu")
			(roundrect_rratio 0.5)
			(chamfer_ratio 0)
			(chamfer top_left bottom_left)
			(net 225 "/Supply/DC-DC AUX, MGT/MGTAVCCAUX_local")
			(pinfunction "2")
			(pintype "passive")
		)
	)
	(footprint "antmicro-footprints:R_0402_1005Metric"
		(layer "F.Cu")
		(at 121.1 162.15 180)
		(descr "Resistor SMD 0402")
		(tags "resistor SMD 0402")
		(property "Reference" "R80"
			(at 0.9 -1.05 0)
			(layer "F.SilkS")
			(effects
				(font
					(size 0.7 0.7)
					(thickness 0.15)
				)
				(justify right bottom)
			)
		)
		(property "Value" "R_10k_0402"
			(at -1.011843 1.772047 0)
			(layer "F.Fab")
			(effects
				(font
					(size 0.7 0.7)
					(thickness 0.15)
				)
				(justify right bottom)
			)
		)
		(property "Datasheet" "https://www.bourns.com/docs/product-datasheets/cr.pdf"
			(at 0 0 180)
			(layer "F.Fab")
			(hide yes)
			(effects
				(font
					(size 1.27 1.27)
					(thickness 0.15)
				)
			)
		)
		(property "MPN" "CR0402-FX-1002GLF"
			(at 0 0 180)
			(unlocked yes)
			(layer "F.Fab")
			(hide yes)
			(effects
				(font
					(size 1 1)
					(thickness 0.15)
				)
			)
		)
		(property "Manufacturer" "Bourns"
			(at 0 0 180)
			(unlocked yes)
			(layer "F.Fab")
			(hide yes)
			(effects
				(font
					(size 1 1)
					(thickness 0.15)
				)
			)
		)
		(property "License" "Apache-2.0"
			(at 0 0 180)
			(unlocked yes)
			(layer "F.Fab")
			(hide yes)
			(effects
				(font
					(size 1 1)
					(thickness 0.15)
				)
			)
		)
		(property "Author" "Antmicro"
			(at 0 0 180)
			(unlocked yes)
			(layer "F.Fab")
			(hide yes)
			(effects
				(font
					(size 1 1)
					(thickness 0.15)
				)
			)
		)
		(property "Val" "10k"
			(at 0 0 180)
			(unlocked yes)
			(layer "F.Fab")
			(hide yes)
			(effects
				(font
					(size 1 1)
					(thickness 0.15)
				)
			)
		)
		(property "Tolerance" "1%"
			(at 0 0 180)
			(unlocked yes)
			(layer "F.Fab")
			(hide yes)
			(effects
				(font
					(size 1 1)
					(thickness 0.15)
				)
			)
		)
		(sheetname "/HDMI + SD Card/")
		(sheetfile "hdmi-sd-card.kicad_sch")
		(attr smd)
		(fp_rect
			(start -0.925 -0.47)
			(end 0.925 0.47)
			(stroke
				(width 0.05)
				(type default)
			)
			(fill no)
			(layer "F.CrtYd")
		)
		(fp_rect
			(start -0.5 -0.25)
			(end 0.5 0.25)
			(stroke
				(width 0.15)
				(type solid)
			)
			(fill no)
			(layer "F.Fab")
		)
		(fp_text user "License: Apache-2.0"
			(at -0.95 5.169 180)
			(layer "F.Fab")
			(effects
				(font
					(size 0.7 0.7)
					(thickness 0.15)
				)
				(justify left bottom)
			)
		)
		(fp_text user "Author: Antmicro"
			(at -0.95 4.169 180)
			(layer "F.Fab")
			(effects
				(font
					(size 0.7 0.7)
					(thickness 0.15)
				)
				(justify left bottom)
			)
		)
		(fp_text user "${REFERENCE}"
			(at -0.95 3.168 180)
			(layer "F.Fab")
			(effects
				(font
					(size 0.7 0.7)
					(thickness 0.15)
				)
				(justify left bottom)
			)
		)
		(pad "1" smd roundrect
			(at -0.48 0 180)
			(size 0.59 0.64)
			(layers "F.Cu" "F.Mask" "F.Paste")
			(roundrect_rratio 0.25)
			(net 663 "Net-(U43-ST)")
			(pintype "passive")
		)
		(pad "2" smd roundrect
			(at 0.48 0 180)
			(size 0.59 0.64)
			(layers "F.Cu" "F.Mask" "F.Paste")
			(roundrect_rratio 0.25)
			(net 797 "+1V8")
			(pintype "passive")
		)
	)
)
